FILE_TYPE=LIBRARY_PARTS;
primitive 'NX3L2267GM';
  pin
    'VCC':
      PIN_NUMBER='(10)';
      PINUSE='POWER';
      NO_LOAD_CHECK='Both';
      NO_IO_CHECK='Both';
      NO_ASSERT_CHECK='TRUE';
      NO_DIR_CHECK='TRUE';
      ALLOW_CONNECT='TRUE';
    '2Z':
      PIN_NUMBER='(6)';
      BIDIRECTIONAL='TRUE';
      INPUT_LOAD='(-0.01,0.01)';
      OUTPUT_LOAD='(1.0,-1.0)';
    '1Y0':
      PIN_NUMBER='(1)';
      BIDIRECTIONAL='TRUE';
      INPUT_LOAD='(-0.01,0.01)';
      OUTPUT_LOAD='(1.0,-1.0)';
    'GND':
      PIN_NUMBER='(5)';
      PINUSE='POWER';
      NO_LOAD_CHECK='Both';
      NO_IO_CHECK='Both';
      NO_ASSERT_CHECK='TRUE';
      NO_DIR_CHECK='TRUE';
      ALLOW_CONNECT='TRUE';
    '1Y1':
      PIN_NUMBER='(2)';
      BIDIRECTIONAL='TRUE';
      INPUT_LOAD='(-0.01,0.01)';
      OUTPUT_LOAD='(1.0,-1.0)';
    '2S':
      PIN_NUMBER='(7)';
      INPUT_LOAD='(-0.01,0.01)';
    '2Y1':
      PIN_NUMBER='(4)';
      BIDIRECTIONAL='TRUE';
      INPUT_LOAD='(-0.01,0.01)';
      OUTPUT_LOAD='(1.0,-1.0)';
    '1Z':
      PIN_NUMBER='(9)';
      BIDIRECTIONAL='TRUE';
      INPUT_LOAD='(-0.01,0.01)';
      OUTPUT_LOAD='(1.0,-1.0)';
    '1S':
      PIN_NUMBER='(8)';
      INPUT_LOAD='(-0.01,0.01)';
    '2Y0':
      PIN_NUMBER='(3)';
      BIDIRECTIONAL='TRUE';
      INPUT_LOAD='(-0.01,0.01)';
      OUTPUT_LOAD='(1.0,-1.0)';
  end_pin;
  body
    PART_NAME='NX3L2267GM';
    BODY_NAME='NX3L2267GM';
    PHYS_DES_PREFIX='U';
    CLASS='IC';
  end_body;
end_primitive;

END.
